(kicad_pcb
	(version 20260206)
	(generator "pcbnew")
	(generator_version "10.0")
	(general
		(thickness 1.6)
		(legacy_teardrops no)
	)
	(paper "A4")
	(title_block
		(title "pdpb — Lightning_PDPB_BRD.brd")
		(comment 1 "Lightning (Wiwynn / Facebook NVMe JBOF) / footprints 981-987 of 1140")
	)
	(layers
		(0 "F.Cu" signal "TOP")
		(4 "In1.Cu" signal "L2GND")
		(6 "In2.Cu" signal "L3")
		(8 "In3.Cu" signal "L4VCC")
		(10 "In4.Cu" signal "L5VCC")
		(12 "In5.Cu" signal "L6")
		(14 "In6.Cu" signal "L7GND")
		(2 "B.Cu" signal "BOTTOM")
		(9 "F.Adhes" user "F.Adhesive")
		(11 "B.Adhes" user "B.Adhesive")
		(13 "F.Paste" user "Package Geometry/Pastemask Top")
		(15 "B.Paste" user "Package Geometry/Pastemask Bottom")
		(5 "F.SilkS" user "Ref Des/Silkscreen Top")
		(7 "B.SilkS" user "Ref Des/Silkscreen Bottom")
		(1 "F.Mask" user "Board Geometry/Soldermask Top")
		(3 "B.Mask" user "Board Geometry/Soldermask Bottom")
		(17 "Dwgs.User" user "User.Drawings")
		(19 "Cmts.User" user "User.Comments")
		(21 "Eco1.User" user "User.Eco1")
		(23 "Eco2.User" user "User.Eco2")
		(25 "Edge.Cuts" user "Board Geometry/Outline")
		(27 "Margin" user)
		(31 "F.CrtYd" user "Package Geometry/Place Bound Top")
		(29 "B.CrtYd" user "Package Geometry/Place Bound Bottom")
		(35 "F.Fab" user "Ref Des/Assembly Top")
		(33 "B.Fab" user "Ref Des/Assembly Bottom")
	)
	(footprint ""
		(layer "F.Cu")
		(at 224.625662 -421.703246 -90)
		(property "Reference" "PR9086"
			(at 0 0 270)
			(layer "F.SilkS")
			(hide yes)
			(effects
				(font
					(size 1.27 1.27)
				)
			)
		)
		(property "Value" "0R6J-3-GP"
			(at -0.0508 -4.8514 270)
			(unlocked yes)
			(layer "F.Fab")
			(hide yes)
			(effects
				(font
					(size 1.016 1.016)
					(thickness 0.1524)
				)
			)
		)
		(property "Device Type" "R1206H28"
			(at 0 -6.3754 270)
			(unlocked yes)
			(layer "F.Fab")
			(hide yes)
			(effects
				(font
					(size 1.016 1.016)
					(thickness 0.1524)
				)
			)
		)
		(duplicate_pad_numbers_are_jumpers no)
		(fp_line
			(start -1.016 2.2352)
			(end -1.016 -2.2352)
			(stroke
				(width 0.1524)
				(type default)
			)
			(layer "F.SilkS")
		)
		(fp_line
			(start 1.016 2.2352)
			(end -1.016 2.2352)
			(stroke
				(width 0.1524)
				(type default)
			)
			(layer "F.SilkS")
		)
		(fp_line
			(start -1.016 -2.2352)
			(end 1.016 -2.2352)
			(stroke
				(width 0.1524)
				(type default)
			)
			(layer "F.SilkS")
		)
		(fp_line
			(start 1.016 -2.2352)
			(end 1.016 2.2352)
			(stroke
				(width 0.1524)
				(type default)
			)
			(layer "F.SilkS")
		)
		(fp_rect
			(start -1.0922 2.3114)
			(end 1.0922 -2.3114)
			(stroke
				(width 0)
				(type default)
			)
			(fill no)
			(layer "F.CrtYd")
		)
		(fp_poly
			(pts
				(xy -1.0922 -2.3114) (xy 1.0922 -2.3114) (xy 1.0922 2.3114) (xy -1.0922 2.3114)
			)
			(stroke
				(width 0)
				(type default)
			)
			(fill no)
			(layer "F.Fab")
		)
		(pad "1" smd rect
			(at 0 -1.397 270)
			(size 1.651 1.27)
			(layers "F.Cu" "F.Mask" "F.Paste")
			(net "P3V3_VIN")
		)
		(pad "2" smd rect
			(at 0 1.397 270)
			(size 1.651 1.27)
			(layers "F.Cu" "F.Mask" "F.Paste")
			(net "P12V")
		)
	)
	(footprint ""
		(layer "F.Cu")
		(at 197.571106 -493.523778)
		(property "Reference" "D18"
			(at 0 0 0)
			(layer "F.SilkS")
			(hide yes)
			(effects
				(font
					(size 1.27 1.27)
				)
			)
		)
		(property "Value" "RB551V30-1-GP"
			(at 0 -6.7818 0)
			(unlocked yes)
			(layer "F.Fab")
			(hide yes)
			(effects
				(font
					(size 1.016 1.016)
					(thickness 0.1524)
				)
			)
		)
		(property "Device Type" "SOD323AKH44"
			(at 0 -8.6868 0)
			(unlocked yes)
			(layer "F.Fab")
			(hide yes)
			(effects
				(font
					(size 1.016 1.016)
					(thickness 0.1524)
				)
			)
		)
		(duplicate_pad_numbers_are_jumpers no)
		(fp_line
			(start -0.889 -1.9304)
			(end 0.889 -1.9304)
			(stroke
				(width 0.1524)
				(type default)
			)
			(layer "F.SilkS")
		)
		(fp_line
			(start -0.889 2.159)
			(end -0.889 -1.9304)
			(stroke
				(width 0.1524)
				(type default)
			)
			(layer "F.SilkS")
		)
		(fp_line
			(start 0.762 2.0574)
			(end -0.762 2.0574)
			(stroke
				(width 0.508)
				(type default)
			)
			(layer "F.SilkS")
		)
		(fp_line
			(start 0.889 -1.9304)
			(end 0.889 2.159)
			(stroke
				(width 0.1524)
				(type default)
			)
			(layer "F.SilkS")
		)
		(fp_line
			(start 0.889 2.159)
			(end -0.889 2.159)
			(stroke
				(width 0.1524)
				(type default)
			)
			(layer "F.SilkS")
		)
		(fp_rect
			(start -1.016 2.3114)
			(end 1.016 -2.0066)
			(stroke
				(width 0)
				(type default)
			)
			(fill no)
			(layer "F.CrtYd")
		)
		(fp_poly
			(pts
				(xy -1.016 -2.0066) (xy 1.016 -2.0066) (xy 1.016 2.3114) (xy -1.016 2.3114)
			)
			(stroke
				(width 0)
				(type default)
			)
			(fill no)
			(layer "F.Fab")
		)
		(pad "A" smd rect
			(at 0 -1.143)
			(size 0.5588 1.016)
			(layers "F.Cu" "F.Mask" "F.Paste")
			(net "SW_SSD0_R")
		)
		(pad "K" smd rect
			(at 0 1.143)
			(size 0.5588 1.016)
			(layers "F.Cu" "F.Mask" "F.Paste")
			(net "SW_SSD0_N")
		)
	)
	(footprint ""
		(layer "F.Cu")
		(at 227.203 -446.913 90)
		(property "Reference" "U197"
			(at 0 0 90)
			(layer "F.SilkS")
			(hide yes)
			(effects
				(font
					(size 1.27 1.27)
				)
			)
		)
		(property "Value" "SN74LVC1G08DCKR-GP"
			(at -2.3368 -8.6868 90)
			(unlocked yes)
			(layer "F.Fab")
			(hide yes)
			(effects
				(font
					(size 1.016 1.016)
					(thickness 0.1524)
				)
			)
		)
		(property "Device Type" "SC70-5H44"
			(at -2.3114 -10.414 90)
			(unlocked yes)
			(layer "F.Fab")
			(hide yes)
			(effects
				(font
					(size 1.016 1.016)
					(thickness 0.1524)
				)
			)
		)
		(duplicate_pad_numbers_are_jumpers no)
		(fp_line
			(start 1.3843 -1.8034)
			(end 1.3843 -1.1176)
			(stroke
				(width 0.3302)
				(type default)
			)
			(layer "F.SilkS")
		)
		(fp_line
			(start 0.6604 -1.8034)
			(end 1.3843 -1.8034)
			(stroke
				(width 0.3302)
				(type default)
			)
			(layer "F.SilkS")
		)
		(fp_line
			(start 1.27 -1.7018)
			(end 1.27 1.7018)
			(stroke
				(width 0.1524)
				(type default)
			)
			(layer "F.SilkS")
		)
		(fp_line
			(start -1.27 -1.7018)
			(end 1.27 -1.7018)
			(stroke
				(width 0.1524)
				(type default)
			)
			(layer "F.SilkS")
		)
		(fp_line
			(start 1.27 1.7018)
			(end -1.27 1.7018)
			(stroke
				(width 0.1524)
				(type default)
			)
			(layer "F.SilkS")
		)
		(fp_line
			(start -1.27 1.7018)
			(end -1.27 -1.7018)
			(stroke
				(width 0.1524)
				(type default)
			)
			(layer "F.SilkS")
		)
		(fp_rect
			(start -1.524 1.9558)
			(end 1.524 -1.9558)
			(stroke
				(width 0)
				(type default)
			)
			(fill no)
			(layer "F.CrtYd")
		)
		(fp_poly
			(pts
				(xy -1.524 -1.9558) (xy 1.524 -1.9558) (xy 1.524 1.9558) (xy -1.524 1.9558)
			)
			(stroke
				(width 0)
				(type default)
			)
			(fill no)
			(layer "F.Fab")
		)
		(pad "1" smd rect
			(at 0.65024 -0.8255 90)
			(size 0.4064 1.2192)
			(layers "F.Cu" "F.Mask" "F.Paste")
			(net "SSD0_CLK0_OE_MOS_N")
		)
		(pad "2" smd rect
			(at 0 -0.8255 90)
			(size 0.4064 1.2192)
			(layers "F.Cu" "F.Mask" "F.Paste")
			(net "ATTN_LED_DR0_N")
		)
		(pad "3" smd rect
			(at -0.65024 -0.8255 90)
			(size 0.4064 1.2192)
			(layers "F.Cu" "F.Mask" "F.Paste")
			(net "GND")
		)
		(pad "4" smd rect
			(at -0.65024 0.8255 90)
			(size 0.4064 1.2192)
			(layers "F.Cu" "F.Mask" "F.Paste")
			(net "ATTN_LED_DR0_AND")
		)
		(pad "5" smd rect
			(at 0.65024 0.8255 90)
			(size 0.4064 1.2192)
			(layers "F.Cu" "F.Mask" "F.Paste")
			(net "P3V3")
		)
	)
	(footprint ""
		(layer "F.Cu")
		(at 233.807 -138.80211 180)
		(property "Reference" "Q43"
			(at 0 0 180)
			(layer "F.SilkS")
			(hide yes)
			(effects
				(font
					(size 1.27 1.27)
				)
			)
		)
		(property "Value" "2N7002A-7-GP"
			(at 0.127 -8.9662 180)
			(unlocked yes)
			(layer "F.Fab")
			(hide yes)
			(effects
				(font
					(size 1.016 1.016)
					(thickness 0.1524)
				)
			)
		)
		(property "Device Type" "SOT23DGS2D4H48"
			(at 0.127 -10.4902 180)
			(unlocked yes)
			(layer "F.Fab")
			(hide yes)
			(effects
				(font
					(size 1.016 1.016)
					(thickness 0.1524)
				)
			)
		)
		(duplicate_pad_numbers_are_jumpers no)
		(fp_line
			(start 1.651 1.778)
			(end 1.651 -1.778)
			(stroke
				(width 0.1524)
				(type default)
			)
			(layer "F.SilkS")
		)
		(fp_line
			(start 1.651 -1.778)
			(end -1.651 -1.778)
			(stroke
				(width 0.1524)
				(type default)
			)
			(layer "F.SilkS")
		)
		(fp_line
			(start -1.651 1.778)
			(end 1.651 1.778)
			(stroke
				(width 0.1524)
				(type default)
			)
			(layer "F.SilkS")
		)
		(fp_line
			(start -1.651 -1.778)
			(end -1.651 1.778)
			(stroke
				(width 0.1524)
				(type default)
			)
			(layer "F.SilkS")
		)
		(fp_poly
			(pts
				(xy -1.778 1.8796) (xy -1.778 -1.8796) (xy 1.778 -1.8796) (xy 1.778 1.8796)
			)
			(stroke
				(width 0)
				(type default)
			)
			(fill no)
			(layer "F.CrtYd")
		)
		(fp_poly
			(pts
				(xy -1.778 1.8796) (xy -1.778 -1.8796) (xy 1.778 -1.8796) (xy 1.778 1.8796)
			)
			(stroke
				(width 0)
				(type default)
			)
			(fill no)
			(layer "F.Fab")
		)
		(pad "D" smd custom
			(at 0 -0.9525 180)
			(size 0.1905 0.1905)
			(layers "F.Cu" "F.Mask" "F.Paste")
			(net "SSD_ACT_DR3_MOS_N")
			(options
				(clearance outline)
				(anchor circle)
			)
			(primitives
				(gr_poly
					(pts
						(arc
							(start -0.1778 0.5715)
							(mid -0.321484 0.511984)
							(end -0.381 0.3683)
						)
						(arc
							(start -0.381 -0.3683)
							(mid -0.321484 -0.511984)
							(end -0.1778 -0.5715)
						)
						(arc
							(start 0.1778 -0.5715)
							(mid 0.321484 -0.511984)
							(end 0.381 -0.3683)
						)
						(arc
							(start 0.381 0.3683)
							(mid 0.321484 0.511984)
							(end 0.1778 0.5715)
						)
					)
					(width 0)
					(fill yes)
				)
			)
		)
		(pad "G" smd custom
			(at -0.98425 0.9525 180)
			(size 0.1905 0.1905)
			(layers "F.Cu" "F.Mask" "F.Paste")
			(net "ATTN_LED_DR3_AND_R")
			(options
				(clearance outline)
				(anchor circle)
			)
			(primitives
				(gr_poly
					(pts
						(arc
							(start -0.1778 0.5715)
							(mid -0.321484 0.511984)
							(end -0.381 0.3683)
						)
						(arc
							(start -0.381 -0.3683)
							(mid -0.321484 -0.511984)
							(end -0.1778 -0.5715)
						)
						(arc
							(start 0.1778 -0.5715)
							(mid 0.321484 -0.511984)
							(end 0.381 -0.3683)
						)
						(arc
							(start 0.381 0.3683)
							(mid 0.321484 0.511984)
							(end 0.1778 0.5715)
						)
					)
					(width 0)
					(fill yes)
				)
			)
		)
		(pad "S" smd custom
			(at 0.98425 0.9525 180)
			(size 0.1905 0.1905)
			(layers "F.Cu" "F.Mask" "F.Paste")
			(net "SSD_ACT_DR3_R")
			(options
				(clearance outline)
				(anchor circle)
			)
			(primitives
				(gr_poly
					(pts
						(arc
							(start -0.1778 0.5715)
							(mid -0.321484 0.511984)
							(end -0.381 0.3683)
						)
						(arc
							(start -0.381 -0.3683)
							(mid -0.321484 -0.511984)
							(end -0.1778 -0.5715)
						)
						(arc
							(start 0.1778 -0.5715)
							(mid 0.321484 -0.511984)
							(end 0.381 -0.3683)
						)
						(arc
							(start 0.381 0.3683)
							(mid 0.321484 0.511984)
							(end 0.1778 0.5715)
						)
					)
					(width 0)
					(fill yes)
				)
			)
		)
	)
	(footprint ""
		(layer "F.Cu")
		(at 220.0402 -395.6558)
		(property "Reference" "PC1236"
			(at 0 0 0)
			(layer "F.SilkS")
			(hide yes)
			(effects
				(font
					(size 1.27 1.27)
				)
			)
		)
		(property "Value" "SC22U25V6KX-GP-U"
			(at -2.860802 -5.279644 0)
			(unlocked yes)
			(layer "F.Fab")
			(hide yes)
			(effects
				(font
					(size 1.016 1.016)
					(thickness 0.1524)
				)
			)
		)
		(property "Device Type" "C1206-TO0D3H75"
			(at -2.860802 -6.803644 0)
			(unlocked yes)
			(layer "F.Fab")
			(hide yes)
			(effects
				(font
					(size 1.016 1.016)
					(thickness 0.1524)
				)
			)
		)
		(duplicate_pad_numbers_are_jumpers no)
		(fp_line
			(start -1.3081 -2.3749)
			(end 1.3081 -2.3749)
			(stroke
				(width 0.1524)
				(type default)
			)
			(layer "F.SilkS")
		)
		(fp_line
			(start -1.3081 2.3749)
			(end -1.3081 -2.3749)
			(stroke
				(width 0.1524)
				(type default)
			)
			(layer "F.SilkS")
		)
		(fp_line
			(start 1.3081 -2.3749)
			(end 1.3081 2.3749)
			(stroke
				(width 0.1524)
				(type default)
			)
			(layer "F.SilkS")
		)
		(fp_line
			(start 1.3081 2.3749)
			(end -1.3081 2.3749)
			(stroke
				(width 0.1524)
				(type default)
			)
			(layer "F.SilkS")
		)
		(fp_rect
			(start -0.8001 1.6002)
			(end 0.8001 -1.6002)
			(stroke
				(width 0)
				(type default)
			)
			(fill no)
			(layer "F.CrtYd")
		)
		(fp_poly
			(pts
				(xy -1.5621 2.4511) (xy -1.5621 1.6002) (xy 0.8001 1.6002) (xy 0.8001 -1.6002) (xy -0.8001 -1.6002)
				(xy -0.8001 1.5875) (xy -1.5621 1.5875) (xy -1.5621 -2.4511) (xy 1.5621 -2.4511) (xy 1.5621 2.4511)
			)
			(stroke
				(width 0)
				(type default)
			)
			(fill no)
			(layer "F.CrtYd")
		)
		(fp_rect
			(start -1.5621 2.4511)
			(end 1.5621 -2.4511)
			(stroke
				(width 0)
				(type default)
			)
			(fill no)
			(layer "F.Fab")
		)
		(pad "1" smd rect
			(at 0 -1.392936)
			(size 2.1082 1.4478)
			(layers "F.Cu" "F.Mask" "F.Paste")
			(net "P12V_SSD1")
		)
		(pad "2" smd rect
			(at 0 1.392936)
			(size 2.1082 1.4478)
			(layers "F.Cu" "F.Mask" "F.Paste")
			(net "GND")
		)
	)
	(footprint ""
		(layer "F.Cu")
		(at 199.222106 -491.110778)
		(property "Reference" "R551"
			(at 0 0 0)
			(layer "F.SilkS")
			(hide yes)
			(effects
				(font
					(size 1.27 1.27)
				)
			)
		)
		(property "Value" "200KR2F-L-GP"
			(at 0.064008 -3.993896 0)
			(unlocked yes)
			(layer "F.Fab")
			(hide yes)
			(effects
				(font
					(size 1.016 1.016)
					(thickness 0.1524)
				)
			)
		)
		(property "Device Type" "R402H16"
			(at 0.064008 -5.517896 0)
			(unlocked yes)
			(layer "F.Fab")
			(hide yes)
			(effects
				(font
					(size 1.016 1.016)
					(thickness 0.1524)
				)
			)
		)
		(duplicate_pad_numbers_are_jumpers no)
		(fp_line
			(start -0.508 -0.9398)
			(end -0.508 0.9398)
			(stroke
				(width 0.1524)
				(type default)
			)
			(layer "F.SilkS")
		)
		(fp_line
			(start 0.508 -0.9398)
			(end -0.508 -0.9398)
			(stroke
				(width 0.1524)
				(type default)
			)
			(layer "F.SilkS")
		)
		(fp_rect
			(start -0.508 0.9398)
			(end 0.508 -0.9398)
			(stroke
				(width 0)
				(type default)
			)
			(fill no)
			(layer "F.CrtYd")
		)
		(fp_rect
			(start -0.508 0.9398)
			(end 0.508 -0.9398)
			(stroke
				(width 0)
				(type default)
			)
			(fill no)
			(layer "F.Fab")
		)
		(pad "1" smd custom
			(at 0 -0.4445)
			(size 0.1397 0.1397)
			(layers "F.Cu" "F.Mask" "F.Paste")
			(net "SW_SSD0_R")
			(options
				(clearance outline)
				(anchor circle)
			)
			(primitives
				(gr_poly
					(pts
						(arc
							(start -0.1778 -0.2794)
							(mid -0.249642 -0.249642)
							(end -0.2794 -0.1778)
						)
						(arc
							(start -0.2794 0.1778)
							(mid -0.249642 0.249642)
							(end -0.1778 0.2794)
						)
						(arc
							(start 0.1778 0.2794)
							(mid 0.249642 0.249642)
							(end 0.2794 0.1778)
						)
						(arc
							(start 0.2794 -0.1778)
							(mid 0.249642 -0.249642)
							(end 0.1778 -0.2794)
						)
					)
					(width 0)
					(fill yes)
				)
			)
		)
		(pad "2" smd custom
			(at 0 0.4445)
			(size 0.1397 0.1397)
			(layers "F.Cu" "F.Mask" "F.Paste")
			(net "SW_SSD0_N")
			(options
				(clearance outline)
				(anchor circle)
			)
			(primitives
				(gr_poly
					(pts
						(arc
							(start -0.1778 -0.2794)
							(mid -0.249642 -0.249642)
							(end -0.2794 -0.1778)
						)
						(arc
							(start -0.2794 0.1778)
							(mid -0.249642 0.249642)
							(end -0.1778 0.2794)
						)
						(arc
							(start 0.1778 0.2794)
							(mid 0.249642 0.249642)
							(end 0.2794 0.1778)
						)
						(arc
							(start 0.2794 -0.1778)
							(mid 0.249642 -0.249642)
							(end 0.1778 -0.2794)
						)
					)
					(width 0)
					(fill yes)
				)
			)
		)
	)
	(footprint ""
		(layer "F.Cu")
		(at 208.153 -190.119)
		(property "Reference" "R554"
			(at 0 0 0)
			(layer "F.SilkS")
			(hide yes)
			(effects
				(font
					(size 1.27 1.27)
				)
			)
		)
		(property "Value" "200KR2F-L-GP"
			(at 0.064008 -3.993896 0)
			(unlocked yes)
			(layer "F.Fab")
			(hide yes)
			(effects
				(font
					(size 1.016 1.016)
					(thickness 0.1524)
				)
			)
		)
		(property "Device Type" "R402H16"
			(at 0.064008 -5.517896 0)
			(unlocked yes)
			(layer "F.Fab")
			(hide yes)
			(effects
				(font
					(size 1.016 1.016)
					(thickness 0.1524)
				)
			)
		)
		(duplicate_pad_numbers_are_jumpers no)
		(fp_line
			(start -0.508 -0.9398)
			(end -0.508 0.9398)
			(stroke
				(width 0.1524)
				(type default)
			)
			(layer "F.SilkS")
		)
		(fp_line
			(start 0.508 -0.9398)
			(end -0.508 -0.9398)
			(stroke
				(width 0.1524)
				(type default)
			)
			(layer "F.SilkS")
		)
		(fp_rect
			(start -0.508 0.9398)
			(end 0.508 -0.9398)
			(stroke
				(width 0)
				(type default)
			)
			(fill no)
			(layer "F.CrtYd")
		)
		(fp_rect
			(start -0.508 0.9398)
			(end 0.508 -0.9398)
			(stroke
				(width 0)
				(type default)
			)
			(fill no)
			(layer "F.Fab")
		)
		(pad "1" smd custom
			(at 0 -0.4445)
			(size 0.1397 0.1397)
			(layers "F.Cu" "F.Mask" "F.Paste")
			(net "SW_SSD3_R")
			(options
				(clearance outline)
				(anchor circle)
			)
			(primitives
				(gr_poly
					(pts
						(arc
							(start -0.1778 -0.2794)
							(mid -0.249642 -0.249642)
							(end -0.2794 -0.1778)
						)
						(arc
							(start -0.2794 0.1778)
							(mid -0.249642 0.249642)
							(end -0.1778 0.2794)
						)
						(arc
							(start 0.1778 0.2794)
							(mid 0.249642 0.249642)
							(end 0.2794 0.1778)
						)
						(arc
							(start 0.2794 -0.1778)
							(mid 0.249642 -0.249642)
							(end 0.1778 -0.2794)
						)
					)
					(width 0)
					(fill yes)
				)
			)
		)
		(pad "2" smd custom
			(at 0 0.4445)
			(size 0.1397 0.1397)
			(layers "F.Cu" "F.Mask" "F.Paste")
			(net "SW_SSD3_N")
			(options
				(clearance outline)
				(anchor circle)
			)
			(primitives
				(gr_poly
					(pts
						(arc
							(start -0.1778 -0.2794)
							(mid -0.249642 -0.249642)
							(end -0.2794 -0.1778)
						)
						(arc
							(start -0.2794 0.1778)
							(mid -0.249642 0.249642)
							(end -0.1778 0.2794)
						)
						(arc
							(start 0.1778 0.2794)
							(mid 0.249642 0.249642)
							(end 0.2794 0.1778)
						)
						(arc
							(start 0.2794 -0.1778)
							(mid 0.249642 -0.249642)
							(end 0.1778 -0.2794)
						)
					)
					(width 0)
					(fill yes)
				)
			)
		)
	)
)
